# BASEBOARD_FAB2 (Tioga Pass) — schematic netlist excerpt (pin names and nets, part order shuffled) for the footprints in the layout excerpt that follows; sources: Cadence DE-HDL packaged netlist, KiCad conversion of Wiwynn_Tioga_Pass_MB.brd

FB25W3  BLM15AG121SN-1GP  pkg DISCRET-G  page 254 : \1\ = XDP_TRST_R_N ; \2\ = XDP_TRST_N
C7L7  CAP  10UF 4V 20% X6S  pkg 0603LF  page 234 : A = PVPP_KLM ; B = GND
FB1U4  FERRITE  30 FB  pkg SMLF  page 169 : A = A_PVNN_STBY_PCH_SENSOR ; B = PVNN_PCH_STBY

(kicad_pcb
	(version 20260206)
	(generator "pcbnew")
	(generator_version "10.0")
	(general
		(thickness 1.6)
		(legacy_teardrops no)
	)
	(paper "A4")
	(title_block
		(title "Wiwynn_Tioga_Pass_MB.brd")
		(comment 1 "Tioga Pass / footprints 3987-3989 of 4770")
	)
	(layers
		(0 "F.Cu" signal "TOP")
		(4 "In1.Cu" signal "L2GND")
		(6 "In2.Cu" signal "L3")
		(8 "In3.Cu" signal "L4GND")
		(10 "In4.Cu" signal "L5")
		(12 "In5.Cu" signal "L6GND")
		(14 "In6.Cu" signal "L7VCC")
		(16 "In7.Cu" signal "L8VCC")
		(18 "In8.Cu" signal "L9GND")
		(20 "In9.Cu" signal "L10")
		(22 "In10.Cu" signal "L11GND")
		(24 "In11.Cu" signal "L12")
		(26 "In12.Cu" signal "L13GND")
		(2 "B.Cu" signal "BOTTOM")
		(9 "F.Adhes" user "F.Adhesive")
		(11 "B.Adhes" user "B.Adhesive")
		(13 "F.Paste" user "Package Geometry/Pastemask Top")
		(15 "B.Paste" user "Package Geometry/Pastemask Bottom")
		(5 "F.SilkS" user "Ref Des/Silkscreen Top")
		(7 "B.SilkS" user "Ref Des/Silkscreen Bottom")
		(1 "F.Mask" user "Board Geometry/Soldermask Top")
		(3 "B.Mask" user "Board Geometry/Soldermask Bottom")
		(17 "Dwgs.User" user "User.Drawings")
		(19 "Cmts.User" user "User.Comments")
		(21 "Eco1.User" user "User.Eco1")
		(23 "Eco2.User" user "User.Eco2")
		(25 "Edge.Cuts" user "Board Geometry/Outline")
		(27 "Margin" user)
		(31 "F.CrtYd" user "Package Geometry/Place Bound Top")
		(29 "B.CrtYd" user "Package Geometry/Place Bound Bottom")
		(35 "F.Fab" user "Ref Des/Assembly Top")
		(33 "B.Fab" user "Ref Des/Assembly Bottom")
	)
	(footprint ""
		(layer "B.Cu")
		(at 154.023568 -144.977612 -90)
		(property "Reference" "C7L7"
			(at 0 0 90)
			(layer "B.SilkS")
			(hide yes)
			(effects
				(font
					(size 1.27 1.27)
				)
				(justify mirror)
			)
		)
		(property "Value" ""
			(at 0 0 90)
			(layer "B.Fab")
			(effects
				(font
					(size 1.27 1.27)
				)
				(justify mirror)
			)
		)
		(duplicate_pad_numbers_are_jumpers no)
		(fp_rect
			(start 0.4953 1.6002)
			(end -0.4953 -0.2032)
			(stroke
				(width 0)
				(type default)
			)
			(fill no)
			(layer "B.CrtYd")
		)
		(fp_line
			(start -0.4953 1.6002)
			(end 0.4953 1.6002)
			(stroke
				(width 0.1)
				(type default)
			)
			(layer "B.Fab")
		)
		(fp_line
			(start 0.4953 1.6002)
			(end 0.4953 -0.2032)
			(stroke
				(width 0.1)
				(type default)
			)
			(layer "B.Fab")
		)
		(fp_line
			(start -0.4953 -0.2032)
			(end -0.4953 1.6002)
			(stroke
				(width 0.1)
				(type default)
			)
			(layer "B.Fab")
		)
		(fp_line
			(start 0.4953 -0.2032)
			(end -0.4953 -0.2032)
			(stroke
				(width 0.1)
				(type default)
			)
			(layer "B.Fab")
		)
		(pad "1" smd rect
			(at 0 0 90)
			(size 0.762 0.889)
			(layers "B.Cu" "B.Mask" "B.Paste")
			(net "PVPP_KLM")
		)
		(pad "2" smd rect
			(at 0 1.397 90)
			(size 0.762 0.889)
			(layers "B.Cu" "B.Mask" "B.Paste")
			(net "GND")
		)
		(zone
			(layer "B.Cu")
			(hatch none 0.5)
			(connect_pads
				(clearance 0)
			)
			(min_thickness 0.25)
			(keepout
				(tracks not_allowed)
				(vias allowed)
				(pads allowed)
				(copperpour not_allowed)
				(footprints allowed)
			)
			(placement
				(enabled no)
				(sheetname "")
			)
			(fill
				(thermal_gap 0.5)
				(thermal_bridge_width 0.5)
				(island_removal_mode 0)
			)
			(polygon
				(pts
					(xy 153.071068 -144.596612) (xy 153.579068 -144.596612) (xy 153.579068 -145.358612) (xy 153.071068 -145.358612)
				)
			)
		)
	)
	(footprint ""
		(layer "B.Cu")
		(at 407.465022 -17.838166 -90)
		(property "Reference" "FB1U4"
			(at 0 0 90)
			(layer "B.SilkS")
			(hide yes)
			(effects
				(font
					(size 1.27 1.27)
				)
				(justify mirror)
			)
		)
		(property "Value" ""
			(at 0 0 90)
			(layer "B.Fab")
			(effects
				(font
					(size 1.27 1.27)
				)
				(justify mirror)
			)
		)
		(duplicate_pad_numbers_are_jumpers no)
		(fp_poly
			(pts
				(xy 0.47625 -0.2413) (xy -0.47625 -0.2413) (xy -0.47625 1.5113) (xy 0.47625 1.5113)
			)
			(stroke
				(width 0)
				(type default)
			)
			(fill no)
			(layer "B.CrtYd")
		)
		(fp_line
			(start -0.47625 1.5113)
			(end 0.47625 1.5113)
			(stroke
				(width 0.1)
				(type default)
			)
			(layer "B.Fab")
		)
		(fp_line
			(start 0.47625 1.5113)
			(end 0.47625 -0.2413)
			(stroke
				(width 0.1)
				(type default)
			)
			(layer "B.Fab")
		)
		(fp_line
			(start -0.47625 -0.2413)
			(end -0.47625 1.5113)
			(stroke
				(width 0.1)
				(type default)
			)
			(layer "B.Fab")
		)
		(fp_line
			(start 0.47625 -0.2413)
			(end -0.47625 -0.2413)
			(stroke
				(width 0.1)
				(type default)
			)
			(layer "B.Fab")
		)
		(pad "1" smd rect
			(at 0 0 90)
			(size 0.762 0.889)
			(layers "B.Cu" "B.Mask" "B.Paste")
			(net "A_PVNN_STBY_PCH_SENSOR")
		)
		(pad "2" smd rect
			(at 0 1.27 90)
			(size 0.762 0.889)
			(layers "B.Cu" "B.Mask" "B.Paste")
			(net "PVNN_PCH_STBY")
		)
		(zone
			(layer "B.Cu")
			(hatch none 0.5)
			(connect_pads
				(clearance 0)
			)
			(min_thickness 0.25)
			(keepout
				(tracks not_allowed)
				(vias allowed)
				(pads allowed)
				(copperpour not_allowed)
				(footprints allowed)
			)
			(placement
				(enabled no)
				(sheetname "")
			)
			(fill
				(thermal_gap 0.5)
				(thermal_bridge_width 0.5)
				(island_removal_mode 0)
			)
			(polygon
				(pts
					(xy 406.639522 -17.452086) (xy 407.015442 -17.452086) (xy 407.015442 -18.219166) (xy 406.639522 -18.219166)
				)
			)
		)
		(zone
			(layer "B.Cu")
			(hatch none 0.5)
			(connect_pads
				(clearance 0)
			)
			(min_thickness 0.25)
			(keepout
				(tracks allowed)
				(vias not_allowed)
				(pads allowed)
				(copperpour not_allowed)
				(footprints allowed)
			)
			(placement
				(enabled no)
				(sheetname "")
			)
			(fill
				(thermal_gap 0.5)
				(thermal_bridge_width 0.5)
				(island_removal_mode 0)
			)
			(polygon
				(pts
					(xy 407.015442 -17.452086) (xy 407.015442 -18.219166) (xy 406.639522 -18.219166) (xy 406.639522 -17.452086)
				)
			)
		)
	)
	(footprint ""
		(layer "B.Cu")
		(at 437.339232 -152.32507 180)
		(property "Reference" "FB25W3"
			(at 0 0 0)
			(layer "B.SilkS")
			(hide yes)
			(effects
				(font
					(size 1.27 1.27)
				)
				(justify mirror)
			)
		)
		(property "Value" "*"
			(at 0.0127 -7.01675 180)
			(unlocked yes)
			(layer "B.Fab")
			(hide yes)
			(effects
				(font
					(size 0.889 0.889)
					(thickness 0.1524)
				)
				(justify mirror)
			)
		)
		(property "Device Type" "BLM15AG121SN-1GP_DISCRET-G-BLMA"
			(at 0.0127 -8.54075 180)
			(unlocked yes)
			(layer "B.Fab")
			(hide yes)
			(effects
				(font
					(size 0.889 0.889)
					(thickness 0.1524)
				)
				(justify mirror)
			)
		)
		(duplicate_pad_numbers_are_jumpers no)
		(fp_line
			(start 0.508 0.9398)
			(end 0.508 0.8636)
			(stroke
				(width 0.1524)
				(type default)
			)
			(layer "B.SilkS")
		)
		(fp_line
			(start 0.508 -0.9398)
			(end 0.508 0.9398)
			(stroke
				(width 0.1524)
				(type default)
			)
			(layer "B.SilkS")
		)
		(fp_line
			(start -0.508 -0.9398)
			(end 0.508 -0.9398)
			(stroke
				(width 0.1524)
				(type default)
			)
			(layer "B.SilkS")
		)
		(fp_rect
			(start 0.508 0.9398)
			(end -0.508 -0.9398)
			(stroke
				(width 0)
				(type default)
			)
			(fill no)
			(layer "B.CrtYd")
		)
		(fp_rect
			(start 0.508 0.9398)
			(end -0.508 -0.9398)
			(stroke
				(width 0)
				(type default)
			)
			(fill no)
			(layer "B.Fab")
		)
		(pad "1" smd custom
			(at 0 -0.4445)
			(size 0.1397 0.1397)
			(layers "B.Cu" "B.Mask" "B.Paste")
			(net "XDP_TRST_R_N")
			(options
				(clearance outline)
				(anchor circle)
			)
			(primitives
				(gr_poly
					(pts
						(arc
							(start -0.1778 0.2794)
							(mid -0.249642 0.249642)
							(end -0.2794 0.1778)
						)
						(arc
							(start -0.2794 -0.1778)
							(mid -0.249642 -0.249642)
							(end -0.1778 -0.2794)
						)
						(arc
							(start 0.1778 -0.2794)
							(mid 0.249642 -0.249642)
							(end 0.2794 -0.1778)
						)
						(arc
							(start 0.2794 0.1778)
							(mid 0.249642 0.249642)
							(end 0.1778 0.2794)
						)
					)
					(width 0)
					(fill yes)
				)
			)
		)
		(pad "2" smd custom
			(at 0 0.4445)
			(size 0.1397 0.1397)
			(layers "B.Cu" "B.Mask" "B.Paste")
			(net "XDP_TRST_N")
			(options
				(clearance outline)
				(anchor circle)
			)
			(primitives
				(gr_poly
					(pts
						(arc
							(start -0.1778 0.2794)
							(mid -0.249642 0.249642)
							(end -0.2794 0.1778)
						)
						(arc
							(start -0.2794 -0.1778)
							(mid -0.249642 -0.249642)
							(end -0.1778 -0.2794)
						)
						(arc
							(start 0.1778 -0.2794)
							(mid 0.249642 -0.249642)
							(end 0.2794 -0.1778)
						)
						(arc
							(start 0.2794 0.1778)
							(mid 0.249642 0.249642)
							(end 0.1778 0.2794)
						)
					)
					(width 0)
					(fill yes)
				)
			)
		)
	)
)
